# SCM (Grand Teton) — schematic netlist excerpt (pin names and nets, part order shuffled) for the footprints in the layout excerpt that follows; sources: Cadence DE-HDL packaged netlist, KiCad conversion of 12092022_DA0F0TMDCD0_F0T_Management_Board_D_brd_V3_OCP.brd

C131  Q_CAP  22UF 6.3V 20% X6S  pkg C0603  page 16 : A = P1V2_AUX ; B = GND
C79  Q_CAP  0.1UF 25V 10% X7R  pkg 0402  page 17 : A = P1V0_STBY_PE_VCC10A ; B = GND

(kicad_pcb
	(version 20260206)
	(generator "pcbnew")
	(generator_version "10.0")
	(general
		(thickness 1.6)
		(legacy_teardrops no)
	)
	(paper "A4")
	(title_block
		(title "12092022_DA0F0TMDCD0_F0T_Management_Board_D_brd_V3_OCP.brd")
		(comment 1 "Grand Teton / footprints 998-999 of 1440")
	)
	(layers
		(0 "F.Cu" signal "TOP")
		(4 "In1.Cu" signal "GND")
		(6 "In2.Cu" signal "IN1")
		(8 "In3.Cu" signal "GND1")
		(10 "In4.Cu" signal "IN2")
		(12 "In5.Cu" signal "VCC")
		(14 "In6.Cu" signal "VCC1")
		(16 "In7.Cu" signal "IN3")
		(18 "In8.Cu" signal "GND2")
		(20 "In9.Cu" signal "IN4")
		(22 "In10.Cu" signal "GND3")
		(2 "B.Cu" signal "BOTTOM")
		(9 "F.Adhes" user "F.Adhesive")
		(11 "B.Adhes" user "B.Adhesive")
		(13 "F.Paste" user "Package Geometry/Pastemask Top")
		(15 "B.Paste" user "Package Geometry/Pastemask Bottom")
		(5 "F.SilkS" user "Ref Des/Silkscreen Top")
		(7 "B.SilkS" user "Ref Des/Silkscreen Bottom")
		(1 "F.Mask" user "Board Geometry/Soldermask Top")
		(3 "B.Mask" user "Board Geometry/Soldermask Bottom")
		(17 "Dwgs.User" user "User.Drawings")
		(19 "Cmts.User" user "User.Comments")
		(21 "Eco1.User" user "User.Eco1")
		(23 "Eco2.User" user "User.Eco2")
		(25 "Edge.Cuts" user "Board Geometry/Outline")
		(27 "Margin" user)
		(31 "F.CrtYd" user "Package Geometry/Place Bound Top")
		(29 "B.CrtYd" user "Package Geometry/Place Bound Bottom")
		(35 "F.Fab" user "Ref Des/Assembly Top")
		(33 "B.Fab" user "Ref Des/Assembly Bottom")
	)
	(footprint ""
		(layer "B.Cu")
		(at 59.109102 -50.71364 90)
		(property "Reference" "C79"
			(at 0 0 90)
			(layer "B.SilkS")
			(hide yes)
			(effects
				(font
					(size 1.27 1.27)
				)
				(justify mirror)
			)
		)
		(property "Value" ""
			(at 0 0 90)
			(layer "B.Fab")
			(effects
				(font
					(size 1.27 1.27)
				)
				(justify mirror)
			)
		)
		(duplicate_pad_numbers_are_jumpers no)
		(fp_line
			(start 0.7874 -0.4064)
			(end -0.7874 -0.4064)
			(stroke
				(width 0.1524)
				(type default)
			)
			(layer "B.SilkS")
		)
		(fp_line
			(start -0.7874 -0.4064)
			(end -0.7874 0.4064)
			(stroke
				(width 0.1524)
				(type default)
			)
			(layer "B.SilkS")
		)
		(fp_line
			(start 0.7874 0.4064)
			(end 0.7874 -0.4064)
			(stroke
				(width 0.1524)
				(type default)
			)
			(layer "B.SilkS")
		)
		(fp_line
			(start -0.7874 0.4064)
			(end 0.7874 0.4064)
			(stroke
				(width 0.1524)
				(type default)
			)
			(layer "B.SilkS")
		)
		(fp_line
			(start 0.67945 -0.305054)
			(end 0.12065 -0.305054)
			(stroke
				(width 0.1)
				(type default)
			)
			(layer "B.Fab")
		)
		(fp_line
			(start 0.12065 -0.305054)
			(end 0.12065 -0.2794)
			(stroke
				(width 0.1)
				(type default)
			)
			(layer "B.Fab")
		)
		(fp_line
			(start -0.12065 -0.3048)
			(end -0.67945 -0.3048)
			(stroke
				(width 0.1)
				(type default)
			)
			(layer "B.Fab")
		)
		(fp_line
			(start -0.67945 -0.3048)
			(end -0.67945 0.3048)
			(stroke
				(width 0.1)
				(type default)
			)
			(layer "B.Fab")
		)
		(fp_line
			(start 0.12065 -0.2794)
			(end -0.12065 -0.2794)
			(stroke
				(width 0.1)
				(type default)
			)
			(layer "B.Fab")
		)
		(fp_line
			(start -0.12065 -0.2794)
			(end -0.12065 -0.3048)
			(stroke
				(width 0.1)
				(type default)
			)
			(layer "B.Fab")
		)
		(fp_line
			(start 0.12065 0.2794)
			(end 0.12065 0.3048)
			(stroke
				(width 0.1)
				(type default)
			)
			(layer "B.Fab")
		)
		(fp_line
			(start -0.120396 0.2794)
			(end 0.12065 0.2794)
			(stroke
				(width 0.1)
				(type default)
			)
			(layer "B.Fab")
		)
		(fp_line
			(start 0.67945 0.3048)
			(end 0.67945 -0.305054)
			(stroke
				(width 0.1)
				(type default)
			)
			(layer "B.Fab")
		)
		(fp_line
			(start 0.12065 0.3048)
			(end 0.67945 0.3048)
			(stroke
				(width 0.1)
				(type default)
			)
			(layer "B.Fab")
		)
		(fp_line
			(start -0.120396 0.3048)
			(end -0.120396 0.2794)
			(stroke
				(width 0.1)
				(type default)
			)
			(layer "B.Fab")
		)
		(fp_line
			(start -0.67945 0.3048)
			(end -0.120396 0.3048)
			(stroke
				(width 0.1)
				(type default)
			)
			(layer "B.Fab")
		)
		(pad "1" smd circle
			(at 0.40005 0 270)
			(size 0 0)
			(layers "B.Cu" "B.Mask" "B.Paste")
			(net "P1V0_STBY_PE_VCC10A")
		)
		(pad "2" smd circle
			(at -0.40005 0 270)
			(size 0 0)
			(layers "B.Cu" "B.Mask" "B.Paste")
			(net "GND")
		)
	)
	(footprint ""
		(layer "B.Cu")
		(at 81.788 -59.055 90)
		(property "Reference" "C131"
			(at 0 0 90)
			(layer "B.SilkS")
			(hide yes)
			(effects
				(font
					(size 1.27 1.27)
				)
				(justify mirror)
			)
		)
		(property "Value" ""
			(at 0 0 90)
			(layer "B.Fab")
			(effects
				(font
					(size 1.27 1.27)
				)
				(justify mirror)
			)
		)
		(duplicate_pad_numbers_are_jumpers no)
		(fp_line
			(start 1.2954 -0.5842)
			(end -1.2954 -0.5842)
			(stroke
				(width 0.1524)
				(type default)
			)
			(layer "B.SilkS")
		)
		(fp_line
			(start 0 -0.5842)
			(end 0 0.5842)
			(stroke
				(width 0.1524)
				(type default)
			)
			(layer "B.SilkS")
		)
		(fp_line
			(start -1.2954 -0.5842)
			(end -1.2954 0.5842)
			(stroke
				(width 0.1524)
				(type default)
			)
			(layer "B.SilkS")
		)
		(fp_line
			(start 1.2954 0.5842)
			(end 1.2954 -0.5842)
			(stroke
				(width 0.1524)
				(type default)
			)
			(layer "B.SilkS")
		)
		(fp_line
			(start -1.2954 0.5842)
			(end 1.2954 0.5842)
			(stroke
				(width 0.1524)
				(type default)
			)
			(layer "B.SilkS")
		)
		(fp_line
			(start 0.8636 -0.4572)
			(end -0.8636 -0.4572)
			(stroke
				(width 0.1)
				(type default)
			)
			(layer "B.Fab")
		)
		(fp_line
			(start -0.8636 -0.4572)
			(end -0.8636 -0.4064)
			(stroke
				(width 0.1)
				(type default)
			)
			(layer "B.Fab")
		)
		(fp_line
			(start 1.1938 -0.4064)
			(end 0.8636 -0.4064)
			(stroke
				(width 0.1)
				(type default)
			)
			(layer "B.Fab")
		)
		(fp_line
			(start 0.8636 -0.4064)
			(end 0.8636 -0.4572)
			(stroke
				(width 0.1)
				(type default)
			)
			(layer "B.Fab")
		)
		(fp_line
			(start -0.8636 -0.4064)
			(end -1.1938 -0.4064)
			(stroke
				(width 0.1)
				(type default)
			)
			(layer "B.Fab")
		)
		(fp_line
			(start -1.1938 -0.4064)
			(end -1.1938 0.4064)
			(stroke
				(width 0.1)
				(type default)
			)
			(layer "B.Fab")
		)
		(fp_line
			(start 1.1938 0.4064)
			(end 1.1938 -0.4064)
			(stroke
				(width 0.1)
				(type default)
			)
			(layer "B.Fab")
		)
		(fp_line
			(start 0.8636 0.4064)
			(end 1.1938 0.4064)
			(stroke
				(width 0.1)
				(type default)
			)
			(layer "B.Fab")
		)
		(fp_line
			(start -0.8636 0.4064)
			(end -0.8636 0.4572)
			(stroke
				(width 0.1)
				(type default)
			)
			(layer "B.Fab")
		)
		(fp_line
			(start -1.1938 0.4064)
			(end -0.8636 0.4064)
			(stroke
				(width 0.1)
				(type default)
			)
			(layer "B.Fab")
		)
		(fp_line
			(start 0.8636 0.4572)
			(end 0.8636 0.4064)
			(stroke
				(width 0.1)
				(type default)
			)
			(layer "B.Fab")
		)
		(fp_line
			(start -0.8636 0.4572)
			(end 0.8636 0.4572)
			(stroke
				(width 0.1)
				(type default)
			)
			(layer "B.Fab")
		)
		(pad "1" smd rect
			(at 0.7366 0)
			(size 0.7112 0.8128)
			(layers "B.Cu" "B.Mask" "B.Paste")
			(net "P1V2_AUX")
		)
		(pad "2" smd rect
			(at -0.7366 0)
			(size 0.7112 0.8128)
			(layers "B.Cu" "B.Mask" "B.Paste")
			(net "GND")
		)
	)
)
